# BASEBOARD_FAB2 (Tioga Pass) — schematic netlist excerpt (pin names and nets, part order shuffled) for the footprints in the layout excerpt that follows; sources: Cadence DE-HDL packaged netlist, KiCad conversion of Wiwynn_Tioga_Pass_MB.brd

C4B9  CAP  2200PF 50V 10% X7R  pkg 0402LF  page 234 : A = VR_COMP_RC_PVPP_KLM ; B = VR_COMP_PVPP_KLM_3
R9F25  RES  100.0 1% CHIP  pkg 0402  page 158 : A = SPA_MID_DBG_RX ; B = UART_MUX_IN_R
C4E9  SC22U16V5MX-4-GP  20%  pkg SMD-BCG5  page 214 : \1\ = VR_FET_SW_P12V_STBY_PVCCIN_CPU0 ; \2\ = GND

(kicad_pcb
	(version 20260206)
	(generator "pcbnew")
	(generator_version "10.0")
	(general
		(thickness 1.6)
		(legacy_teardrops no)
	)
	(paper "A4")
	(title_block
		(title "Wiwynn_Tioga_Pass_MB.brd")
		(comment 1 "Tioga Pass / footprints 699-701 of 4770")
	)
	(layers
		(0 "F.Cu" signal "TOP")
		(4 "In1.Cu" signal "L2GND")
		(6 "In2.Cu" signal "L3")
		(8 "In3.Cu" signal "L4GND")
		(10 "In4.Cu" signal "L5")
		(12 "In5.Cu" signal "L6GND")
		(14 "In6.Cu" signal "L7VCC")
		(16 "In7.Cu" signal "L8VCC")
		(18 "In8.Cu" signal "L9GND")
		(20 "In9.Cu" signal "L10")
		(22 "In10.Cu" signal "L11GND")
		(24 "In11.Cu" signal "L12")
		(26 "In12.Cu" signal "L13GND")
		(2 "B.Cu" signal "BOTTOM")
		(9 "F.Adhes" user "F.Adhesive")
		(11 "B.Adhes" user "B.Adhesive")
		(13 "F.Paste" user "Package Geometry/Pastemask Top")
		(15 "B.Paste" user "Package Geometry/Pastemask Bottom")
		(5 "F.SilkS" user "Ref Des/Silkscreen Top")
		(7 "B.SilkS" user "Ref Des/Silkscreen Bottom")
		(1 "F.Mask" user "Board Geometry/Soldermask Top")
		(3 "B.Mask" user "Board Geometry/Soldermask Bottom")
		(17 "Dwgs.User" user "User.Drawings")
		(19 "Cmts.User" user "User.Comments")
		(21 "Eco1.User" user "User.Eco1")
		(23 "Eco2.User" user "User.Eco2")
		(25 "Edge.Cuts" user "Board Geometry/Outline")
		(27 "Margin" user)
		(31 "F.CrtYd" user "Package Geometry/Place Bound Top")
		(29 "B.CrtYd" user "Package Geometry/Place Bound Bottom")
		(35 "F.Fab" user "Ref Des/Assembly Top")
		(33 "B.Fab" user "Ref Des/Assembly Bottom")
	)
	(footprint ""
		(layer "F.Cu")
		(at 176.0855 -131.318 90)
		(property "Reference" "C4B9"
			(at 0 0 90)
			(layer "F.SilkS")
			(hide yes)
			(effects
				(font
					(size 1.27 1.27)
				)
			)
		)
		(property "Value" ""
			(at 0 0 90)
			(layer "F.Fab")
			(effects
				(font
					(size 1.27 1.27)
				)
			)
		)
		(duplicate_pad_numbers_are_jumpers no)
		(fp_poly
			(pts
				(xy 0.3048 -0.1016) (xy 0.3048 0.9906) (xy -0.3048 0.9906) (xy -0.3048 -0.1016)
			)
			(stroke
				(width 0)
				(type default)
			)
			(fill no)
			(layer "F.CrtYd")
		)
		(fp_line
			(start 0.3048 -0.1016)
			(end -0.3048 -0.1016)
			(stroke
				(width 0.1)
				(type default)
			)
			(layer "F.Fab")
		)
		(fp_line
			(start -0.3048 -0.1016)
			(end -0.3048 0.9906)
			(stroke
				(width 0.1)
				(type default)
			)
			(layer "F.Fab")
		)
		(fp_line
			(start 0.3048 0.9906)
			(end 0.3048 -0.1016)
			(stroke
				(width 0.1)
				(type default)
			)
			(layer "F.Fab")
		)
		(fp_line
			(start -0.3048 0.9906)
			(end 0.3048 0.9906)
			(stroke
				(width 0.1)
				(type default)
			)
			(layer "F.Fab")
		)
		(pad "1" smd rect
			(at 0 0 90)
			(size 0.508 0.508)
			(layers "F.Cu" "F.Mask" "F.Paste")
			(net "VR_COMP_RC_PVPP_KLM")
		)
		(pad "2" smd rect
			(at 0 0.889 90)
			(size 0.508 0.508)
			(layers "F.Cu" "F.Mask" "F.Paste")
			(net "VR_COMP_PVPP_KLM_3")
		)
		(zone
			(layer "F.Cu")
			(hatch none 0.5)
			(connect_pads
				(clearance 0)
			)
			(min_thickness 0.25)
			(keepout
				(tracks allowed)
				(vias not_allowed)
				(pads allowed)
				(copperpour not_allowed)
				(footprints allowed)
			)
			(placement
				(enabled no)
				(sheetname "")
			)
			(fill
				(thermal_gap 0.5)
				(thermal_bridge_width 0.5)
				(island_removal_mode 0)
			)
			(polygon
				(pts
					(xy 176.3395 -131.064) (xy 176.3395 -131.572) (xy 176.7205 -131.572) (xy 176.7205 -131.064)
				)
			)
		)
		(zone
			(layer "F.Cu")
			(hatch none 0.5)
			(connect_pads
				(clearance 0)
			)
			(min_thickness 0.25)
			(keepout
				(tracks not_allowed)
				(vias allowed)
				(pads allowed)
				(copperpour not_allowed)
				(footprints allowed)
			)
			(placement
				(enabled no)
				(sheetname "")
			)
			(fill
				(thermal_gap 0.5)
				(thermal_bridge_width 0.5)
				(island_removal_mode 0)
			)
			(polygon
				(pts
					(xy 176.7205 -131.064) (xy 176.7205 -131.572) (xy 176.3395 -131.572) (xy 176.3395 -131.064)
				)
			)
		)
	)
	(footprint ""
		(layer "F.Cu")
		(at 488.974638 -28.42768 180)
		(property "Reference" "R9F25"
			(at 0 0 180)
			(layer "F.SilkS")
			(hide yes)
			(effects
				(font
					(size 1.27 1.27)
				)
			)
		)
		(property "Value" ""
			(at 0 0 180)
			(layer "F.Fab")
			(effects
				(font
					(size 1.27 1.27)
				)
			)
		)
		(duplicate_pad_numbers_are_jumpers no)
		(fp_poly
			(pts
				(xy -0.2794 -0.1016) (xy 0.2794 -0.1016) (xy 0.2794 0.9906) (xy -0.2794 0.9906)
			)
			(stroke
				(width 0)
				(type default)
			)
			(fill no)
			(layer "F.CrtYd")
		)
		(fp_line
			(start 0.2794 0.9906)
			(end 0.2794 -0.1016)
			(stroke
				(width 0.1)
				(type default)
			)
			(layer "F.Fab")
		)
		(fp_line
			(start 0.2794 -0.1016)
			(end -0.2794 -0.1016)
			(stroke
				(width 0.1)
				(type default)
			)
			(layer "F.Fab")
		)
		(fp_line
			(start -0.2794 0.9906)
			(end 0.2794 0.9906)
			(stroke
				(width 0.1)
				(type default)
			)
			(layer "F.Fab")
		)
		(fp_line
			(start -0.2794 -0.1016)
			(end -0.2794 0.9906)
			(stroke
				(width 0.1)
				(type default)
			)
			(layer "F.Fab")
		)
		(pad "1" smd rect
			(at 0 0 180)
			(size 0.508 0.508)
			(layers "F.Cu" "F.Mask" "F.Paste")
			(net "SPA_MID_DBG_RX")
		)
		(pad "2" smd rect
			(at 0 0.889 180)
			(size 0.508 0.508)
			(layers "F.Cu" "F.Mask" "F.Paste")
			(net "UART_MUX_IN_R")
		)
		(zone
			(layer "F.Cu")
			(hatch none 0.5)
			(connect_pads
				(clearance 0)
			)
			(min_thickness 0.25)
			(keepout
				(tracks not_allowed)
				(vias allowed)
				(pads allowed)
				(copperpour not_allowed)
				(footprints allowed)
			)
			(placement
				(enabled no)
				(sheetname "")
			)
			(fill
				(thermal_gap 0.5)
				(thermal_bridge_width 0.5)
				(island_removal_mode 0)
			)
			(polygon
				(pts
					(xy 489.228638 -29.06268) (xy 488.720638 -29.06268) (xy 488.720638 -28.68168) (xy 489.228638 -28.68168)
				)
			)
		)
		(zone
			(layer "F.Cu")
			(hatch none 0.5)
			(connect_pads
				(clearance 0)
			)
			(min_thickness 0.25)
			(keepout
				(tracks allowed)
				(vias not_allowed)
				(pads allowed)
				(copperpour not_allowed)
				(footprints allowed)
			)
			(placement
				(enabled no)
				(sheetname "")
			)
			(fill
				(thermal_gap 0.5)
				(thermal_bridge_width 0.5)
				(island_removal_mode 0)
			)
			(polygon
				(pts
					(xy 489.228638 -28.68168) (xy 488.720638 -28.68168) (xy 488.720638 -29.06268) (xy 489.228638 -29.06268)
				)
			)
		)
	)
	(footprint ""
		(layer "F.Cu")
		(at 188.22797 -60.461144 180)
		(property "Reference" "C4E9"
			(at 0 0 180)
			(layer "F.SilkS")
			(hide yes)
			(effects
				(font
					(size 1.27 1.27)
				)
			)
		)
		(property "Value" "*"
			(at -0.0762 -6.2357 180)
			(unlocked yes)
			(layer "F.Fab")
			(hide yes)
			(effects
				(font
					(size 1.27 1.016)
					(thickness 0.1524)
				)
			)
		)
		(property "Device Type" "SC22U16V5MX-4-GP_SMD-BCG5-SC22A"
			(at -0.0762 -8.2677 180)
			(unlocked yes)
			(layer "F.Fab")
			(hide yes)
			(effects
				(font
					(size 1.27 1.016)
					(thickness 0.1524)
				)
			)
		)
		(duplicate_pad_numbers_are_jumpers no)
		(fp_line
			(start 0.635 0)
			(end -0.635 0)
			(stroke
				(width 0.508)
				(type default)
			)
			(layer "F.SilkS")
		)
		(fp_rect
			(start -0.9652 1.778)
			(end 0.9652 -1.778)
			(stroke
				(width 0)
				(type default)
			)
			(fill no)
			(layer "F.CrtYd")
		)
		(fp_poly
			(pts
				(xy -0.9652 -1.778) (xy 0.9652 -1.778) (xy 0.9652 1.778) (xy -0.9652 1.778)
			)
			(stroke
				(width 0)
				(type default)
			)
			(fill no)
			(layer "F.Fab")
		)
		(pad "1" smd rect
			(at 0 -0.9652 180)
			(size 1.397 1.143)
			(layers "F.Cu" "F.Mask" "F.Paste")
			(net "VR_FET_SW_P12V_STBY_PVCCIN_CPU0")
		)
		(pad "2" smd rect
			(at 0 0.9652 180)
			(size 1.397 1.143)
			(layers "F.Cu" "F.Mask" "F.Paste")
			(net "GND")
		)
	)
)
